(kicad_pcb
	(version 20260206)
	(generator "pcbnew")
	(generator_version "10.0")
	(general
		(thickness 1.6)
		(legacy_teardrops no)
	)
	(paper "A4")
	(title_block
		(title "netronome-mezz — pcbd0082-001_rev01_jul9_a.brd")
		(comment 1 "Open CloudServer (Microsoft) / footprints 139-147 of 714")
	)
	(layers
		(0 "F.Cu" signal "TOP")
		(4 "In1.Cu" signal "02_GND")
		(6 "In2.Cu" signal "03_SIG")
		(8 "In3.Cu" signal "04_SIG")
		(10 "In4.Cu" signal "05_GND")
		(12 "In5.Cu" signal "06_PWR1")
		(14 "In6.Cu" signal "07_SIG")
		(16 "In7.Cu" signal "08_SIG")
		(18 "In8.Cu" signal "09_GND")
		(2 "B.Cu" signal "BOTTOM")
		(9 "F.Adhes" user "F.Adhesive")
		(11 "B.Adhes" user "B.Adhesive")
		(13 "F.Paste" user "Package Geometry/Pastemask Top")
		(15 "B.Paste" user "Package Geometry/Pastemask Bottom")
		(5 "F.SilkS" user "Ref Des/Silkscreen Top")
		(7 "B.SilkS" user "Ref Des/Silkscreen Bottom")
		(1 "F.Mask" user "Board Geometry/Soldermask Top")
		(3 "B.Mask" user "Board Geometry/Soldermask Bottom")
		(17 "Dwgs.User" user "User.Drawings")
		(19 "Cmts.User" user "User.Comments")
		(21 "Eco1.User" user "User.Eco1")
		(23 "Eco2.User" user "User.Eco2")
		(25 "Edge.Cuts" user "Board Geometry/Outline")
		(27 "Margin" user)
		(31 "F.CrtYd" user "Package Geometry/Place Bound Top")
		(29 "B.CrtYd" user "Package Geometry/Place Bound Bottom")
		(35 "F.Fab" user "Ref Des/Assembly Top")
		(33 "B.Fab" user "Ref Des/Assembly Bottom")
		(45 "User.4" user "COMPVAL_TYPE_BOTTOM")
	)
	(footprint ""
		(layer "F.Cu")
		(at 80.772 46.4312 180)
		(property "Reference" "R109"
			(at 0.73533 -0.8128 90)
			(unlocked yes)
			(layer "F.SilkS")
			(effects
				(font
					(size 0.7874 0.5842)
					(thickness 0.127)
				)
				(justify left)
			)
		)
		(property "Value" "2.2"
			(at -0.148158 1.3462 270)
			(unlocked yes)
			(layer "F.Fab")
			(hide yes)
			(effects
				(font
					(size 1.27 0.9652)
					(thickness 0.000001)
				)
				(justify left)
			)
		)
		(property "Device Type" "REST0114"
			(at -0.148158 1.3462 270)
			(unlocked yes)
			(layer "F.Fab")
			(hide yes)
			(effects
				(font
					(size 1.27 0.9652)
					(thickness 0.000001)
				)
				(justify left)
			)
		)
		(duplicate_pad_numbers_are_jumpers no)
		(fp_poly
			(pts
				(xy 0.635 1.0668) (xy 0.635 -1.0668) (xy -0.635 -1.0668) (xy -0.635 1.0668)
			)
			(stroke
				(width 0)
				(type default)
			)
			(fill no)
			(layer "F.CrtYd")
		)
		(fp_line
			(start 0.254 0.508)
			(end -0.254 0.508)
			(stroke
				(width 0.0254)
				(type default)
			)
			(layer "F.Fab")
		)
		(fp_line
			(start 0.254 -0.508)
			(end 0.254 0.508)
			(stroke
				(width 0.0254)
				(type default)
			)
			(layer "F.Fab")
		)
		(fp_line
			(start -0.254 0.508)
			(end -0.254 -0.508)
			(stroke
				(width 0.0254)
				(type default)
			)
			(layer "F.Fab")
		)
		(fp_line
			(start -0.254 -0.508)
			(end 0.254 -0.508)
			(stroke
				(width 0.0254)
				(type default)
			)
			(layer "F.Fab")
		)
		(pad "1" smd rect
			(at 0 -0.4191 180)
			(size 0.508 0.5334)
			(layers "F.Cu" "F.Mask" "F.Paste")
			(net "11N2258")
		)
		(pad "2" smd rect
			(at 0 0.4191 180)
			(size 0.508 0.5334)
			(layers "F.Cu" "F.Mask" "F.Paste")
			(net "11N2253")
		)
		(zone
			(layer "F.Cu")
			(hatch none 0.5)
			(connect_pads
				(clearance 0)
			)
			(min_thickness 0.25)
			(keepout
				(tracks not_allowed)
				(vias allowed)
				(pads allowed)
				(copperpour not_allowed)
				(footprints allowed)
			)
			(placement
				(enabled no)
				(sheetname "")
			)
			(fill
				(thermal_gap 0.5)
				(thermal_bridge_width 0.5)
				(island_removal_mode 0)
			)
			(polygon
				(pts
					(xy 80.7466 46.4566) (xy 80.7466 46.4058) (xy 80.7974 46.4058) (xy 80.7974 46.4566)
				)
			)
		)
	)
	(footprint ""
		(layer "F.Cu")
		(at 83.7438 22.987 180)
		(property "Reference" "R211"
			(at 0 0 180)
			(layer "F.SilkS")
			(hide yes)
			(effects
				(font
					(size 1.27 1.27)
				)
			)
		)
		(property "Value" "39.0"
			(at -0.148158 1.3462 270)
			(unlocked yes)
			(layer "F.Fab")
			(hide yes)
			(effects
				(font
					(size 1.27 0.9652)
					(thickness 0.000001)
				)
				(justify left)
			)
		)
		(property "Device Type" "REST0108"
			(at -0.148158 1.3462 270)
			(unlocked yes)
			(layer "F.Fab")
			(hide yes)
			(effects
				(font
					(size 1.27 0.9652)
					(thickness 0.000001)
				)
				(justify left)
			)
		)
		(duplicate_pad_numbers_are_jumpers no)
		(fp_poly
			(pts
				(xy 0.635 1.0668) (xy 0.635 -1.0668) (xy -0.635 -1.0668) (xy -0.635 1.0668)
			)
			(stroke
				(width 0)
				(type default)
			)
			(fill no)
			(layer "F.CrtYd")
		)
		(fp_line
			(start 0.254 0.508)
			(end -0.254 0.508)
			(stroke
				(width 0.0254)
				(type default)
			)
			(layer "F.Fab")
		)
		(fp_line
			(start 0.254 -0.508)
			(end 0.254 0.508)
			(stroke
				(width 0.0254)
				(type default)
			)
			(layer "F.Fab")
		)
		(fp_line
			(start -0.254 0.508)
			(end -0.254 -0.508)
			(stroke
				(width 0.0254)
				(type default)
			)
			(layer "F.Fab")
		)
		(fp_line
			(start -0.254 -0.508)
			(end 0.254 -0.508)
			(stroke
				(width 0.0254)
				(type default)
			)
			(layer "F.Fab")
		)
		(pad "1" smd rect
			(at 0 -0.4191 180)
			(size 0.508 0.5334)
			(layers "F.Cu" "F.Mask" "F.Paste")
			(net "DDR0_32A_A5")
		)
		(pad "2" smd rect
			(at 0 0.4191 180)
			(size 0.508 0.5334)
			(layers "F.Cu" "F.Mask" "F.Paste")
			(net "DDR_VTT")
		)
		(zone
			(layer "F.Cu")
			(hatch none 0.5)
			(connect_pads
				(clearance 0)
			)
			(min_thickness 0.25)
			(keepout
				(tracks not_allowed)
				(vias allowed)
				(pads allowed)
				(copperpour not_allowed)
				(footprints allowed)
			)
			(placement
				(enabled no)
				(sheetname "")
			)
			(fill
				(thermal_gap 0.5)
				(thermal_bridge_width 0.5)
				(island_removal_mode 0)
			)
			(polygon
				(pts
					(xy 83.7184 23.0124) (xy 83.7184 22.9616) (xy 83.7692 22.9616) (xy 83.7692 23.0124)
				)
			)
		)
	)
	(footprint ""
		(layer "F.Cu")
		(at 20.955 47.498)
		(property "Reference" "TP44"
			(at 0.635 2.18567 0)
			(unlocked yes)
			(layer "F.SilkS")
			(effects
				(font
					(size 0.7874 0.5842)
					(thickness 0.127)
				)
				(justify left)
			)
		)
		(property "Value" "*"
			(at -0.4826 -0.14732 0)
			(unlocked yes)
			(layer "F.Fab")
			(hide yes)
			(effects
				(font
					(size 1.27 0.9652)
					(thickness 0.000001)
				)
				(justify left)
			)
		)
		(property "Device Type" "TP_SMALL"
			(at -0.4826 -0.14732 0)
			(unlocked yes)
			(layer "F.Fab")
			(hide yes)
			(effects
				(font
					(size 1.27 0.9652)
					(thickness 0.000001)
				)
				(justify left)
			)
		)
		(duplicate_pad_numbers_are_jumpers no)
		(fp_line
			(start -0.8636 -0.8636)
			(end -0.8636 0.8636)
			(stroke
				(width 0.1524)
				(type default)
			)
			(layer "F.SilkS")
		)
		(fp_line
			(start -0.8636 0.8636)
			(end 0.8636 0.8636)
			(stroke
				(width 0.1524)
				(type default)
			)
			(layer "F.SilkS")
		)
		(fp_line
			(start 0.8636 -0.8636)
			(end -0.8636 -0.8636)
			(stroke
				(width 0.1524)
				(type default)
			)
			(layer "F.SilkS")
		)
		(fp_line
			(start 0.8636 0.8636)
			(end 0.8636 -0.8636)
			(stroke
				(width 0.1524)
				(type default)
			)
			(layer "F.SilkS")
		)
		(fp_poly
			(pts
				(xy -0.635 -0.635) (xy -0.635 0.635) (xy 0.635 0.635) (xy 0.635 -0.635)
			)
			(stroke
				(width 0)
				(type default)
			)
			(fill no)
			(layer "F.CrtYd")
		)
		(pad "1" smd rect
			(at 0 0)
			(size 1.27 1.27)
			(layers "F.Cu" "F.Mask" "F.Paste")
			(net "DDR_1.8V")
		)
	)
	(footprint ""
		(layer "F.Cu")
		(at 24.384 29.337 180)
		(property "Reference" "R65"
			(at 0 0 180)
			(layer "F.SilkS")
			(hide yes)
			(effects
				(font
					(size 1.27 1.27)
				)
			)
		)
		(property "Value" "4.75K"
			(at -0.148158 1.3462 270)
			(unlocked yes)
			(layer "F.Fab")
			(hide yes)
			(effects
				(font
					(size 1.27 0.9652)
					(thickness 0.000001)
				)
				(justify left)
			)
		)
		(property "Device Type" "REST4024"
			(at -0.148158 1.3462 270)
			(unlocked yes)
			(layer "F.Fab")
			(hide yes)
			(effects
				(font
					(size 1.27 0.9652)
					(thickness 0.000001)
				)
				(justify left)
			)
		)
		(duplicate_pad_numbers_are_jumpers no)
		(fp_poly
			(pts
				(xy 0.635 1.0668) (xy 0.635 -1.0668) (xy -0.635 -1.0668) (xy -0.635 1.0668)
			)
			(stroke
				(width 0)
				(type default)
			)
			(fill no)
			(layer "F.CrtYd")
		)
		(fp_line
			(start 0.254 0.508)
			(end -0.254 0.508)
			(stroke
				(width 0.0254)
				(type default)
			)
			(layer "F.Fab")
		)
		(fp_line
			(start 0.254 -0.508)
			(end 0.254 0.508)
			(stroke
				(width 0.0254)
				(type default)
			)
			(layer "F.Fab")
		)
		(fp_line
			(start -0.254 0.508)
			(end -0.254 -0.508)
			(stroke
				(width 0.0254)
				(type default)
			)
			(layer "F.Fab")
		)
		(fp_line
			(start -0.254 -0.508)
			(end 0.254 -0.508)
			(stroke
				(width 0.0254)
				(type default)
			)
			(layer "F.Fab")
		)
		(pad "1" smd rect
			(at 0 -0.4191 180)
			(size 0.508 0.5334)
			(layers "F.Cu" "F.Mask" "F.Paste")
			(net "DEBUG_CPLD_PGRM_JTAG_TCK")
		)
		(pad "2" smd rect
			(at 0 0.4191 180)
			(size 0.508 0.5334)
			(layers "F.Cu" "F.Mask" "F.Paste")
			(net "GND")
		)
		(zone
			(layer "F.Cu")
			(hatch none 0.5)
			(connect_pads
				(clearance 0)
			)
			(min_thickness 0.25)
			(keepout
				(tracks not_allowed)
				(vias allowed)
				(pads allowed)
				(copperpour not_allowed)
				(footprints allowed)
			)
			(placement
				(enabled no)
				(sheetname "")
			)
			(fill
				(thermal_gap 0.5)
				(thermal_bridge_width 0.5)
				(island_removal_mode 0)
			)
			(polygon
				(pts
					(xy 24.3586 29.3624) (xy 24.3586 29.3116) (xy 24.4094 29.3116) (xy 24.4094 29.3624)
				)
			)
		)
	)
	(footprint ""
		(layer "F.Cu")
		(at 4.064 36.83)
		(property "Reference" "TP16"
			(at -1.397 -1.37033 0)
			(unlocked yes)
			(layer "F.SilkS")
			(effects
				(font
					(size 0.7874 0.5842)
					(thickness 0.127)
				)
				(justify left)
			)
		)
		(property "Value" "*"
			(at -0.4826 -0.14732 0)
			(unlocked yes)
			(layer "F.Fab")
			(hide yes)
			(effects
				(font
					(size 1.27 0.9652)
					(thickness 0.000001)
				)
				(justify left)
			)
		)
		(property "Device Type" "TP_SMALL"
			(at -0.4826 -0.14732 0)
			(unlocked yes)
			(layer "F.Fab")
			(hide yes)
			(effects
				(font
					(size 1.27 0.9652)
					(thickness 0.000001)
				)
				(justify left)
			)
		)
		(duplicate_pad_numbers_are_jumpers no)
		(fp_line
			(start -0.8636 -0.8636)
			(end -0.8636 0.8636)
			(stroke
				(width 0.1524)
				(type default)
			)
			(layer "F.SilkS")
		)
		(fp_line
			(start -0.8636 0.8636)
			(end 0.8636 0.8636)
			(stroke
				(width 0.1524)
				(type default)
			)
			(layer "F.SilkS")
		)
		(fp_line
			(start 0.8636 -0.8636)
			(end -0.8636 -0.8636)
			(stroke
				(width 0.1524)
				(type default)
			)
			(layer "F.SilkS")
		)
		(fp_line
			(start 0.8636 0.8636)
			(end 0.8636 -0.8636)
			(stroke
				(width 0.1524)
				(type default)
			)
			(layer "F.SilkS")
		)
		(fp_poly
			(pts
				(xy -0.635 -0.635) (xy -0.635 0.635) (xy 0.635 0.635) (xy 0.635 -0.635)
			)
			(stroke
				(width 0)
				(type default)
			)
			(fill no)
			(layer "F.CrtYd")
		)
		(pad "1" smd rect
			(at 0 0)
			(size 1.27 1.27)
			(layers "F.Cu" "F.Mask" "F.Paste")
			(net "PSU_I2C_SDA")
		)
	)
	(footprint ""
		(layer "F.Cu")
		(at 79.248 32.576414)
		(property "Reference" "R231"
			(at -0.35433 3.618586 90)
			(unlocked yes)
			(layer "F.SilkS")
			(effects
				(font
					(size 0.7874 0.5842)
					(thickness 0.127)
				)
				(justify left)
			)
		)
		(property "Value" "39.0"
			(at -0.148158 1.3462 90)
			(unlocked yes)
			(layer "F.Fab")
			(hide yes)
			(effects
				(font
					(size 1.27 0.9652)
					(thickness 0.000001)
				)
				(justify left)
			)
		)
		(property "Device Type" "REST0108"
			(at -0.148158 1.3462 90)
			(unlocked yes)
			(layer "F.Fab")
			(hide yes)
			(effects
				(font
					(size 1.27 0.9652)
					(thickness 0.000001)
				)
				(justify left)
			)
		)
		(duplicate_pad_numbers_are_jumpers no)
		(fp_poly
			(pts
				(xy 0.635 1.0668) (xy 0.635 -1.0668) (xy -0.635 -1.0668) (xy -0.635 1.0668)
			)
			(stroke
				(width 0)
				(type default)
			)
			(fill no)
			(layer "F.CrtYd")
		)
		(fp_line
			(start -0.254 -0.508)
			(end 0.254 -0.508)
			(stroke
				(width 0.0254)
				(type default)
			)
			(layer "F.Fab")
		)
		(fp_line
			(start -0.254 0.508)
			(end -0.254 -0.508)
			(stroke
				(width 0.0254)
				(type default)
			)
			(layer "F.Fab")
		)
		(fp_line
			(start 0.254 -0.508)
			(end 0.254 0.508)
			(stroke
				(width 0.0254)
				(type default)
			)
			(layer "F.Fab")
		)
		(fp_line
			(start 0.254 0.508)
			(end -0.254 0.508)
			(stroke
				(width 0.0254)
				(type default)
			)
			(layer "F.Fab")
		)
		(pad "1" smd rect
			(at 0 -0.4191)
			(size 0.508 0.5334)
			(layers "F.Cu" "F.Mask" "F.Paste")
			(net "DDR0_32A_CKE0")
		)
		(pad "2" smd rect
			(at 0 0.4191)
			(size 0.508 0.5334)
			(layers "F.Cu" "F.Mask" "F.Paste")
			(net "DDR_VTT")
		)
		(zone
			(layer "F.Cu")
			(hatch none 0.5)
			(connect_pads
				(clearance 0)
			)
			(min_thickness 0.25)
			(keepout
				(tracks not_allowed)
				(vias allowed)
				(pads allowed)
				(copperpour not_allowed)
				(footprints allowed)
			)
			(placement
				(enabled no)
				(sheetname "")
			)
			(fill
				(thermal_gap 0.5)
				(thermal_bridge_width 0.5)
				(island_removal_mode 0)
			)
			(polygon
				(pts
					(xy 79.2734 32.551014) (xy 79.2734 32.601814) (xy 79.2226 32.601814) (xy 79.2226 32.551014)
				)
			)
		)
	)
	(footprint ""
		(layer "F.Cu")
		(at 31.75 42.545 -90)
		(property "Reference" "C50"
			(at 0 0 270)
			(layer "F.SilkS")
			(hide yes)
			(effects
				(font
					(size 1.27 1.27)
				)
			)
		)
		(property "Value" "1000PF"
			(at -0.091846 0.2921 0)
			(unlocked yes)
			(layer "F.Fab")
			(hide yes)
			(effects
				(font
					(size 0.7874 0.5842)
					(thickness 0.2032)
				)
				(justify left)
			)
		)
		(property "Device Type" "CAPC0083"
			(at -0.091846 0.2921 0)
			(unlocked yes)
			(layer "F.Fab")
			(hide yes)
			(effects
				(font
					(size 0.7874 0.5842)
					(thickness 0.2032)
				)
				(justify left)
			)
		)
		(duplicate_pad_numbers_are_jumpers no)
		(fp_poly
			(pts
				(xy 0.635 1.0668) (xy 0.635 -1.0668) (xy -0.635 -1.0668) (xy -0.635 1.0668)
			)
			(stroke
				(width 0)
				(type default)
			)
			(fill no)
			(layer "F.CrtYd")
		)
		(fp_line
			(start -0.254 0.508)
			(end -0.254 -0.508)
			(stroke
				(width 0.0254)
				(type default)
			)
			(layer "F.Fab")
		)
		(fp_line
			(start 0.254 0.508)
			(end -0.254 0.508)
			(stroke
				(width 0.0254)
				(type default)
			)
			(layer "F.Fab")
		)
		(fp_line
			(start -0.254 -0.508)
			(end 0.254 -0.508)
			(stroke
				(width 0.0254)
				(type default)
			)
			(layer "F.Fab")
		)
		(fp_line
			(start 0.254 -0.508)
			(end 0.254 0.508)
			(stroke
				(width 0.0254)
				(type default)
			)
			(layer "F.Fab")
		)
		(pad "1" smd rect
			(at 0 -0.4191 270)
			(size 0.508 0.5334)
			(layers "F.Cu" "F.Mask" "F.Paste")
			(net "10N2535")
		)
		(pad "2" smd rect
			(at 0 0.4191 270)
			(size 0.508 0.5334)
			(layers "F.Cu" "F.Mask" "F.Paste")
			(net "GND")
		)
		(zone
			(layer "F.Cu")
			(hatch none 0.5)
			(connect_pads
				(clearance 0)
			)
			(min_thickness 0.25)
			(keepout
				(tracks not_allowed)
				(vias allowed)
				(pads allowed)
				(copperpour not_allowed)
				(footprints allowed)
			)
			(placement
				(enabled no)
				(sheetname "")
			)
			(fill
				(thermal_gap 0.5)
				(thermal_bridge_width 0.5)
				(island_removal_mode 0)
			)
			(polygon
				(pts
					(xy 31.7754 42.5704) (xy 31.7246 42.5704) (xy 31.7246 42.5196) (xy 31.7754 42.5196)
				)
			)
		)
	)
	(footprint ""
		(layer "F.Cu")
		(at 5.715 36.957)
		(property "Reference" "TP22"
			(at -0.254 -1.37033 0)
			(unlocked yes)
			(layer "F.SilkS")
			(effects
				(font
					(size 0.7874 0.5842)
					(thickness 0.127)
				)
				(justify left)
			)
		)
		(property "Value" "*"
			(at -0.4826 -0.14732 0)
			(unlocked yes)
			(layer "F.Fab")
			(hide yes)
			(effects
				(font
					(size 1.27 0.9652)
					(thickness 0.000001)
				)
				(justify left)
			)
		)
		(property "Device Type" "TP_SMALL"
			(at -0.4826 -0.14732 0)
			(unlocked yes)
			(layer "F.Fab")
			(hide yes)
			(effects
				(font
					(size 1.27 0.9652)
					(thickness 0.000001)
				)
				(justify left)
			)
		)
		(duplicate_pad_numbers_are_jumpers no)
		(fp_line
			(start -0.8636 -0.8636)
			(end -0.8636 0.8636)
			(stroke
				(width 0.1524)
				(type default)
			)
			(layer "F.SilkS")
		)
		(fp_line
			(start -0.8636 0.8636)
			(end 0.8636 0.8636)
			(stroke
				(width 0.1524)
				(type default)
			)
			(layer "F.SilkS")
		)
		(fp_line
			(start 0.8636 -0.8636)
			(end -0.8636 -0.8636)
			(stroke
				(width 0.1524)
				(type default)
			)
			(layer "F.SilkS")
		)
		(fp_line
			(start 0.8636 0.8636)
			(end 0.8636 -0.8636)
			(stroke
				(width 0.1524)
				(type default)
			)
			(layer "F.SilkS")
		)
		(fp_poly
			(pts
				(xy -0.635 -0.635) (xy -0.635 0.635) (xy 0.635 0.635) (xy 0.635 -0.635)
			)
			(stroke
				(width 0)
				(type default)
			)
			(fill no)
			(layer "F.CrtYd")
		)
		(pad "1" smd rect
			(at 0 0)
			(size 1.27 1.27)
			(layers "F.Cu" "F.Mask" "F.Paste")
			(net "CPLD_GPIO_0")
		)
	)
	(footprint ""
		(layer "F.Cu")
		(at 64.77 46.609 180)
		(property "Reference" "R99"
			(at 0 0 180)
			(layer "F.SilkS")
			(hide yes)
			(effects
				(font
					(size 1.27 1.27)
				)
			)
		)
		(property "Value" "4.75K"
			(at -0.148158 1.3462 270)
			(unlocked yes)
			(layer "F.Fab")
			(hide yes)
			(effects
				(font
					(size 1.27 0.9652)
					(thickness 0.000001)
				)
				(justify left)
			)
		)
		(property "Device Type" "REST4024"
			(at -0.148158 1.3462 270)
			(unlocked yes)
			(layer "F.Fab")
			(hide yes)
			(effects
				(font
					(size 1.27 0.9652)
					(thickness 0.000001)
				)
				(justify left)
			)
		)
		(duplicate_pad_numbers_are_jumpers no)
		(fp_poly
			(pts
				(xy 0.635 1.0668) (xy 0.635 -1.0668) (xy -0.635 -1.0668) (xy -0.635 1.0668)
			)
			(stroke
				(width 0)
				(type default)
			)
			(fill no)
			(layer "F.CrtYd")
		)
		(fp_line
			(start 0.254 0.508)
			(end -0.254 0.508)
			(stroke
				(width 0.0254)
				(type default)
			)
			(layer "F.Fab")
		)
		(fp_line
			(start 0.254 -0.508)
			(end 0.254 0.508)
			(stroke
				(width 0.0254)
				(type default)
			)
			(layer "F.Fab")
		)
		(fp_line
			(start -0.254 0.508)
			(end -0.254 -0.508)
			(stroke
				(width 0.0254)
				(type default)
			)
			(layer "F.Fab")
		)
		(fp_line
			(start -0.254 -0.508)
			(end 0.254 -0.508)
			(stroke
				(width 0.0254)
				(type default)
			)
			(layer "F.Fab")
		)
		(pad "1" smd rect
			(at 0 -0.4191 180)
			(size 0.508 0.5334)
			(layers "F.Cu" "F.Mask" "F.Paste")
			(net "VDD_5.0V_PGOOD")
		)
		(pad "2" smd rect
			(at 0 0.4191 180)
			(size 0.508 0.5334)
			(layers "F.Cu" "F.Mask" "F.Paste")
			(net "EXT_3.3V")
		)
		(zone
			(layer "F.Cu")
			(hatch none 0.5)
			(connect_pads
				(clearance 0)
			)
			(min_thickness 0.25)
			(keepout
				(tracks not_allowed)
				(vias allowed)
				(pads allowed)
				(copperpour not_allowed)
				(footprints allowed)
			)
			(placement
				(enabled no)
				(sheetname "")
			)
			(fill
				(thermal_gap 0.5)
				(thermal_bridge_width 0.5)
				(island_removal_mode 0)
			)
			(polygon
				(pts
					(xy 64.7446 46.6344) (xy 64.7446 46.5836) (xy 64.7954 46.5836) (xy 64.7954 46.6344)
				)
			)
		)
	)
)
